(kicad_pcb
	(version 20260206)
	(generator "pcbnew")
	(generator_version "10.0")
	(general
		(thickness 1.21888)
		(legacy_teardrops no)
	)
	(paper "A4")
	(title_block
		(title "timecard-v9 — TimeCard-DC-V9_EXP.PcbDoc")
		(comment 1 "Time Appliance Project (Time Card) / footprints 109-116 of 402")
	)
	(layers
		(0 "F.Cu" signal "TOP")
		(4 "In1.Cu" signal "SGND")
		(6 "In2.Cu" signal "IN1")
		(8 "In3.Cu" signal "IN2")
		(10 "In4.Cu" signal "SGND1")
		(2 "B.Cu" signal "BOTTOM")
		(9 "F.Adhes" user "F.Adhesive")
		(11 "B.Adhes" user "B.Adhesive")
		(13 "F.Paste" user "Top Paste")
		(15 "B.Paste" user "Bottom Paste")
		(5 "F.SilkS" user "Top Overlay")
		(7 "B.SilkS" user "Bottom Overlay")
		(1 "F.Mask" user "Top Solder")
		(3 "B.Mask" user "Bottom Solder")
		(17 "Dwgs.User" user "User.Drawings")
		(19 "Cmts.User" user "User.Comments")
		(21 "Eco1.User" user "User.Eco1")
		(23 "Eco2.User" user "User.Eco2")
		(25 "Edge.Cuts" user)
		(27 "Margin" user)
		(31 "F.CrtYd" user "Top Courtyard")
		(29 "B.CrtYd" user "Bottom Courtyard")
		(35 "F.Fab" user "Top Component Center")
		(33 "B.Fab" user "Bottom Component Center")
	)
	(footprint "Vault:FP-BME280-MFG"
		(layer "F.Cu")
		(at 105.60369 87.71708 -90)
		(property "Reference" "U14"
			(at 2.073069 0.92859 180)
			(unlocked yes)
			(layer "F.SilkS")
			(effects
				(font
					(size 0.762 0.762)
					(thickness 0.2286)
				)
			)
		)
		(property "Value" "BME280"
			(at 2.9069 3.443471 270)
			(unlocked yes)
			(layer "F.SilkS")
			(hide yes)
			(effects
				(font
					(size 0.762 0.762)
					(thickness 0.2286)
				)
			)
		)
		(sheetname "05-GPS_IMU_SENSORS")
		(sheetfile "05-GPS_IMU_SENSORS.kicad_sch")
		(duplicate_pad_numbers_are_jumpers no)
		(fp_line
			(start 1.3 1.55)
			(end -1.3 1.55)
			(stroke
				(width 0.2)
				(type solid)
			)
			(layer "F.SilkS")
		)
		(fp_line
			(start 1.3 -1.55)
			(end -1.3 -1.55)
			(stroke
				(width 0.2)
				(type solid)
			)
			(layer "F.SilkS")
		)
		(fp_circle
			(center 1.85 -0.975)
			(end 1.725 -0.975)
			(stroke
				(width 0.25)
				(type solid)
			)
			(fill no)
			(layer "F.SilkS")
		)
		(fp_line
			(start -1.8 1.8)
			(end -1.8 -1.8)
			(stroke
				(width 0.2)
				(type solid)
			)
			(layer "F.CrtYd")
		)
		(fp_line
			(start 1.8 1.8)
			(end -1.8 1.8)
			(stroke
				(width 0.2)
				(type solid)
			)
			(layer "F.CrtYd")
		)
		(fp_line
			(start 1.8 1.8)
			(end 1.8 -1.8)
			(stroke
				(width 0.2)
				(type solid)
			)
			(layer "F.CrtYd")
		)
		(fp_line
			(start 1.8 -1.8)
			(end -1.8 -1.8)
			(stroke
				(width 0.2)
				(type solid)
			)
			(layer "F.CrtYd")
		)
		(fp_line
			(start -1.8 1.8)
			(end -1.8 -1.8)
			(stroke
				(width 0.2)
				(type solid)
			)
			(layer "F.Fab")
		)
		(fp_line
			(start 1.8 1.8)
			(end -1.8 1.8)
			(stroke
				(width 0.2)
				(type solid)
			)
			(layer "F.Fab")
		)
		(fp_line
			(start 1.8 1.8)
			(end 1.8 -1.8)
			(stroke
				(width 0.2)
				(type solid)
			)
			(layer "F.Fab")
		)
		(fp_line
			(start 0 0.5)
			(end 0 -0.5)
			(stroke
				(width 0.1)
				(type solid)
			)
			(layer "F.Fab")
		)
		(fp_line
			(start 0.5 0)
			(end -0.5 0)
			(stroke
				(width 0.1)
				(type solid)
			)
			(layer "F.Fab")
		)
		(fp_line
			(start 1.8 -1.8)
			(end -1.8 -1.8)
			(stroke
				(width 0.2)
				(type solid)
			)
			(layer "F.Fab")
		)
		(fp_text user "${REFERENCE}"
			(at 0 0.28425 270)
			(unlocked yes)
			(layer "F.Fab")
			(effects
				(font
					(face "Arial")
					(size 0.63 0.63)
					(thickness 0.1)
				)
				(justify left bottom)
			)
		)
		(pad "1" smd rect
			(at 1.025 -0.975 270)
			(size 0.5 0.35)
			(layers "F.Cu" "F.Mask" "F.Paste")
			(net "GND")
			(solder_mask_margin 0)
			(solder_paste_margin 0)
		)
		(pad "2" smd rect
			(at 1.025 -0.325 270)
			(size 0.5 0.35)
			(layers "F.Cu" "F.Mask" "F.Paste")
			(net "+3.3V")
			(solder_mask_margin 0)
			(solder_paste_margin 0)
		)
		(pad "3" smd rect
			(at 1.025 0.325 270)
			(size 0.5 0.35)
			(layers "F.Cu" "F.Mask" "F.Paste")
			(net "SENS_I2C_SDA")
			(solder_mask_margin 0)
			(solder_paste_margin 0)
		)
		(pad "4" smd rect
			(at 1.025 0.975 270)
			(size 0.5 0.35)
			(layers "F.Cu" "F.Mask" "F.Paste")
			(net "SENS_I2C_SCL")
			(solder_mask_margin 0)
			(solder_paste_margin 0)
		)
		(pad "5" smd rect
			(at -1.025 0.975 270)
			(size 0.5 0.35)
			(layers "F.Cu" "F.Mask" "F.Paste")
			(net "GND")
			(solder_mask_margin 0)
			(solder_paste_margin 0)
		)
		(pad "6" smd rect
			(at -1.025 0.325 270)
			(size 0.5 0.35)
			(layers "F.Cu" "F.Mask" "F.Paste")
			(net "+3.3V")
			(solder_mask_margin 0)
			(solder_paste_margin 0)
		)
		(pad "7" smd rect
			(at -1.025 -0.325 270)
			(size 0.5 0.35)
			(layers "F.Cu" "F.Mask" "F.Paste")
			(net "GND")
			(solder_mask_margin 0)
			(solder_paste_margin 0)
		)
		(pad "8" smd rect
			(at -1.025 -0.975 270)
			(size 0.5 0.35)
			(layers "F.Cu" "F.Mask" "F.Paste")
			(net "+3.3V")
			(solder_mask_margin 0)
			(solder_paste_margin 0)
		)
	)
	(footprint "Vault:RESC1005X40X25LL05T10"
		(layer "F.Cu")
		(at 122.9216 78.4162)
		(property "Reference" "R177"
			(at 2.4032 0.126921 0)
			(unlocked yes)
			(layer "F.SilkS")
			(effects
				(font
					(size 0.762 0.762)
					(thickness 0.2032)
				)
			)
		)
		(property "Value" "49.9_1%_0402"
			(at -2.579871 8.798265 270)
			(unlocked yes)
			(layer "F.SilkS")
			(hide yes)
			(effects
				(font
					(size 0.762 0.762)
					(thickness 0.2032)
				)
			)
		)
		(sheetname "11-M2_RCB_MUX")
		(sheetfile "11-M2_RCB_MUX.kicad_sch")
		(duplicate_pad_numbers_are_jumpers no)
		(pad "1" smd rect
			(at -0.375 0 90)
			(size 0.45 0.5)
			(layers "F.Cu" "F.Mask" "F.Paste")
			(net "NetR177_1")
		)
		(pad "2" smd rect
			(at 0.375 0 90)
			(size 0.45 0.5)
			(layers "F.Cu" "F.Mask" "F.Paste")
			(net "GPS1_PIN12")
		)
	)
	(footprint "Vault:FP-TAJE-MFG"
		(layer "F.Cu")
		(at 98.4216 67.8162 90)
		(property "Reference" "C71"
			(at 4.673079 -2.045995 0)
			(unlocked yes)
			(layer "F.SilkS")
			(effects
				(font
					(size 0.762 0.762)
					(thickness 0.254)
				)
			)
		)
		(property "Value" "470uF_10V_2917"
			(at -5.818351 8.162815 0)
			(unlocked yes)
			(layer "F.SilkS")
			(hide yes)
			(effects
				(font
					(size 0.762 0.762)
					(thickness 0.2032)
				)
			)
		)
		(sheetname "03-POWER")
		(sheetfile "03-POWER.kicad_sch")
		(duplicate_pad_numbers_are_jumpers no)
		(fp_line
			(start 3.75 -2.25)
			(end 3.75 -1.875)
			(stroke
				(width 0.2)
				(type solid)
			)
			(layer "F.SilkS")
		)
		(fp_line
			(start -3.75 -2.25)
			(end 3.75 -2.25)
			(stroke
				(width 0.2)
				(type solid)
			)
			(layer "F.SilkS")
		)
		(fp_line
			(start -3.75 -2.25)
			(end -3.75 -1.875)
			(stroke
				(width 0.2)
				(type solid)
			)
			(layer "F.SilkS")
		)
		(fp_line
			(start 4.675 -0.3)
			(end 4.675 0.3)
			(stroke
				(width 0.2)
				(type solid)
			)
			(layer "F.SilkS")
		)
		(fp_line
			(start 4.375 0)
			(end 4.975 0)
			(stroke
				(width 0.2)
				(type solid)
			)
			(layer "F.SilkS")
		)
		(fp_line
			(start 3.75 1.875)
			(end 3.75 2.25)
			(stroke
				(width 0.2)
				(type solid)
			)
			(layer "F.SilkS")
		)
		(fp_line
			(start -3.75 1.875)
			(end -3.75 2.25)
			(stroke
				(width 0.2)
				(type solid)
			)
			(layer "F.SilkS")
		)
		(fp_line
			(start -3.75 2.25)
			(end 3.75 2.25)
			(stroke
				(width 0.2)
				(type solid)
			)
			(layer "F.SilkS")
		)
		(fp_line
			(start 4.1 -2.35)
			(end 4.1 2.35)
			(stroke
				(width 0.2)
				(type solid)
			)
			(layer "F.CrtYd")
		)
		(fp_line
			(start -4.1 -2.35)
			(end 4.1 -2.35)
			(stroke
				(width 0.2)
				(type solid)
			)
			(layer "F.CrtYd")
		)
		(fp_line
			(start -4.1 -2.35)
			(end -4.1 2.35)
			(stroke
				(width 0.2)
				(type solid)
			)
			(layer "F.CrtYd")
		)
		(fp_line
			(start -4.1 2.35)
			(end 4.1 2.35)
			(stroke
				(width 0.2)
				(type solid)
			)
			(layer "F.CrtYd")
		)
		(fp_line
			(start 4.1 -2.35)
			(end 4.1 2.35)
			(stroke
				(width 0.2)
				(type solid)
			)
			(layer "F.Fab")
		)
		(fp_line
			(start -4.1 -2.35)
			(end 4.1 -2.35)
			(stroke
				(width 0.2)
				(type solid)
			)
			(layer "F.Fab")
		)
		(fp_line
			(start -4.1 -2.35)
			(end -4.1 2.35)
			(stroke
				(width 0.2)
				(type solid)
			)
			(layer "F.Fab")
		)
		(fp_line
			(start 0 -0.5)
			(end 0 0.5)
			(stroke
				(width 0.1)
				(type solid)
			)
			(layer "F.Fab")
		)
		(fp_line
			(start -0.5 0)
			(end 0.5 0)
			(stroke
				(width 0.1)
				(type solid)
			)
			(layer "F.Fab")
		)
		(fp_line
			(start -4.1 2.35)
			(end 4.1 2.35)
			(stroke
				(width 0.2)
				(type solid)
			)
			(layer "F.Fab")
		)
		(fp_text user "${REFERENCE}"
			(at 0 0.28425 90)
			(unlocked yes)
			(layer "F.Fab")
			(effects
				(font
					(face "Arial")
					(size 0.63 0.63)
					(thickness 0.1)
				)
				(justify left bottom)
			)
		)
		(pad "1" smd rect
			(at -3 0 90)
			(size 2 3)
			(layers "F.Cu" "F.Mask" "F.Paste")
			(net "GND")
			(solder_mask_margin 0)
			(solder_paste_margin 0)
		)
		(pad "2" smd rect
			(at 3 0 90)
			(size 2 3)
			(layers "F.Cu" "F.Mask" "F.Paste")
			(net "+5.0V")
			(solder_mask_margin 0)
			(solder_paste_margin 0)
		)
	)
	(footprint "Vault:FP-TAJE-MFG"
		(layer "F.Cu")
		(at 160.1216 94.2162)
		(property "Reference" "C4"
			(at 1.50937 3.402815 0)
			(unlocked yes)
			(layer "F.SilkS")
			(effects
				(font
					(size 0.762 0.762)
					(thickness 0.2286)
				)
				(justify left bottom)
			)
		)
		(property "Value" "470uF_10V_2917"
			(at 11.7497 7.622845 0)
			(unlocked yes)
			(layer "F.SilkS")
			(hide yes)
			(effects
				(font
					(size 0.762 0.762)
					(thickness 0.2286)
				)
				(justify left bottom)
			)
		)
		(sheetname "03-POWER")
		(sheetfile "03-POWER.kicad_sch")
		(duplicate_pad_numbers_are_jumpers no)
		(fp_line
			(start -3.75 -2.25)
			(end 3.75 -2.25)
			(stroke
				(width 0.2)
				(type solid)
			)
			(layer "F.SilkS")
		)
		(fp_line
			(start -3.75 -1.875)
			(end -3.75 -2.25)
			(stroke
				(width 0.2)
				(type solid)
			)
			(layer "F.SilkS")
		)
		(fp_line
			(start -3.75 2.25)
			(end -3.75 1.875)
			(stroke
				(width 0.2)
				(type solid)
			)
			(layer "F.SilkS")
		)
		(fp_line
			(start -3.75 2.25)
			(end 3.75 2.25)
			(stroke
				(width 0.2)
				(type solid)
			)
			(layer "F.SilkS")
		)
		(fp_line
			(start 3.75 -1.875)
			(end 3.75 -2.25)
			(stroke
				(width 0.2)
				(type solid)
			)
			(layer "F.SilkS")
		)
		(fp_line
			(start 3.75 2.25)
			(end 3.75 1.875)
			(stroke
				(width 0.2)
				(type solid)
			)
			(layer "F.SilkS")
		)
		(fp_line
			(start 4.375 0)
			(end 4.975 0)
			(stroke
				(width 0.2)
				(type solid)
			)
			(layer "F.SilkS")
		)
		(fp_line
			(start 4.675 0.3)
			(end 4.675 -0.3)
			(stroke
				(width 0.2)
				(type solid)
			)
			(layer "F.SilkS")
		)
		(fp_line
			(start -4.1 -2.35)
			(end 4.1 -2.35)
			(stroke
				(width 0.2)
				(type solid)
			)
			(layer "F.CrtYd")
		)
		(fp_line
			(start -4.1 2.35)
			(end -4.1 -2.35)
			(stroke
				(width 0.2)
				(type solid)
			)
			(layer "F.CrtYd")
		)
		(fp_line
			(start -4.1 2.35)
			(end 4.1 2.35)
			(stroke
				(width 0.2)
				(type solid)
			)
			(layer "F.CrtYd")
		)
		(fp_line
			(start 4.1 2.35)
			(end 4.1 -2.35)
			(stroke
				(width 0.2)
				(type solid)
			)
			(layer "F.CrtYd")
		)
		(fp_line
			(start -4.1 -2.35)
			(end 4.1 -2.35)
			(stroke
				(width 0.2)
				(type solid)
			)
			(layer "F.Fab")
		)
		(fp_line
			(start -4.1 2.35)
			(end -4.1 -2.35)
			(stroke
				(width 0.2)
				(type solid)
			)
			(layer "F.Fab")
		)
		(fp_line
			(start -4.1 2.35)
			(end 4.1 2.35)
			(stroke
				(width 0.2)
				(type solid)
			)
			(layer "F.Fab")
		)
		(fp_line
			(start -0.5 0)
			(end 0.5 0)
			(stroke
				(width 0.1)
				(type solid)
			)
			(layer "F.Fab")
		)
		(fp_line
			(start 0 0.5)
			(end 0 -0.5)
			(stroke
				(width 0.1)
				(type solid)
			)
			(layer "F.Fab")
		)
		(fp_line
			(start 4.1 2.35)
			(end 4.1 -2.35)
			(stroke
				(width 0.2)
				(type solid)
			)
			(layer "F.Fab")
		)
		(fp_text user "${REFERENCE}"
			(at 0 0.28425 360)
			(unlocked yes)
			(layer "F.Fab")
			(effects
				(font
					(face "Arial")
					(size 0.63 0.63)
					(thickness 0.1)
				)
				(justify left bottom)
			)
		)
		(pad "1" smd rect
			(at -3 0)
			(size 2 3)
			(layers "F.Cu" "F.Mask" "F.Paste")
			(net "GND")
			(solder_mask_margin 0)
			(solder_paste_margin 0)
		)
		(pad "2" smd rect
			(at 3 0)
			(size 2 3)
			(layers "F.Cu" "F.Mask" "F.Paste")
			(net "+3.3V")
			(solder_mask_margin 0)
			(solder_paste_margin 0)
		)
	)
	(footprint "Vault:RESC1005X40X25LL05T10"
		(layer "F.Cu")
		(at 117.7216 80.8162)
		(property "Reference" "R172"
			(at -0.7968 -1.173079 0)
			(unlocked yes)
			(layer "F.SilkS")
			(effects
				(font
					(size 0.762 0.762)
					(thickness 0.2032)
				)
			)
		)
		(property "Value" "DNI_49.9_1%_0402"
			(at -2.579871 11.71832 270)
			(unlocked yes)
			(layer "F.SilkS")
			(hide yes)
			(effects
				(font
					(size 0.762 0.762)
					(thickness 0.2032)
				)
			)
		)
		(sheetname "11-M2_RCB_MUX")
		(sheetfile "11-M2_RCB_MUX.kicad_sch")
		(duplicate_pad_numbers_are_jumpers no)
		(pad "1" smd rect
			(at -0.375 0 90)
			(size 0.45 0.5)
			(layers "F.Cu" "F.Mask" "F.Paste")
			(net "GPS1_PIN11")
		)
		(pad "2" smd rect
			(at 0.375 0 90)
			(size 0.45 0.5)
			(layers "F.Cu" "F.Mask" "F.Paste")
			(net "M2_GPS1_PIN11")
		)
	)
	(footprint "Vault:RESC1005X40X25NL05T05"
		(layer "F.Cu")
		(at 152.6216 115.1162)
		(property "Reference" "R94"
			(at -2.0714 -0.073079 0)
			(unlocked yes)
			(layer "F.SilkS")
			(effects
				(font
					(size 0.762 0.762)
					(thickness 0.2286)
				)
			)
		)
		(property "Value" "27_1%_0402"
			(at -2.935481 7.78247 270)
			(unlocked yes)
			(layer "F.SilkS")
			(hide yes)
			(effects
				(font
					(size 0.762 0.762)
					(thickness 0.2286)
				)
			)
		)
		(sheetname "08-DIPSwitches_I2C")
		(sheetfile "08-DIPSwitches_I2C.kicad_sch")
		(duplicate_pad_numbers_are_jumpers no)
		(pad "1" smd rect
			(at -0.45 0 90)
			(size 0.55 0.55)
			(layers "F.Cu" "F.Mask" "F.Paste")
			(net "FPGA_MAC_UART_TX")
		)
		(pad "2" smd rect
			(at 0.45 0 90)
			(size 0.55 0.55)
			(layers "F.Cu" "F.Mask" "F.Paste")
			(net "NetR94_2")
		)
	)
	(footprint "Vault:M08A_N"
		(layer "F.Cu")
		(at 130.7216 86.3162 90)
		(property "Reference" "U3"
			(at 2.428605 -2.873079 90)
			(unlocked yes)
			(layer "F.SilkS")
			(effects
				(font
					(size 0.762 0.762)
					(thickness 0.2286)
				)
			)
		)
		(property "Value" "DS90LV027AQMA"
			(at 6.35958 4.332471 90)
			(unlocked yes)
			(layer "F.SilkS")
			(hide yes)
			(effects
				(font
					(size 0.762 0.762)
					(thickness 0.2286)
				)
			)
		)
		(sheetname "06-MAC")
		(sheetfile "06-MAC.kicad_sch")
		(duplicate_pad_numbers_are_jumpers no)
		(fp_line
			(start 0.9 -2.5)
			(end 0.9 2.5)
			(stroke
				(width 0.2)
				(type solid)
			)
			(layer "F.SilkS")
		)
		(fp_line
			(start -0.9 -2.5)
			(end 0.9 -2.5)
			(stroke
				(width 0.2)
				(type solid)
			)
			(layer "F.SilkS")
		)
		(fp_line
			(start -0.9 -2.5)
			(end -0.9 2.5)
			(stroke
				(width 0.2)
				(type solid)
			)
			(layer "F.SilkS")
		)
		(fp_line
			(start -0.9 2.5)
			(end 0.9 2.5)
			(stroke
				(width 0.2)
				(type solid)
			)
			(layer "F.SilkS")
		)
		(fp_circle
			(center -2.4 -2.755)
			(end -2.275 -2.755)
			(stroke
				(width 0.25)
				(type solid)
			)
			(fill no)
			(layer "F.SilkS")
		)
		(fp_circle
			(center -0.1 -1.7)
			(end 0.1 -1.7)
			(stroke
				(width 0.4)
				(type solid)
			)
			(fill no)
			(layer "F.SilkS")
		)
		(pad "1" smd oval
			(at -2.4 -1.905 180)
			(size 0.6 2.2)
			(layers "F.Cu" "F.Mask" "F.Paste")
			(net "+3.3V")
		)
		(pad "2" smd oval
			(at -2.4 -0.635 180)
			(size 0.6 2.2)
			(layers "F.Cu" "F.Mask" "F.Paste")
			(net "FPGA_MAC_PPS_IN1-")
		)
		(pad "3" smd oval
			(at -2.4 0.635 180)
			(size 0.6 2.2)
			(layers "F.Cu" "F.Mask" "F.Paste")
			(net "FPGA_MAC_PPS_DIFF_IN0")
		)
		(pad "4" smd oval
			(at -2.4 1.905 180)
			(size 0.6 2.2)
			(layers "F.Cu" "F.Mask" "F.Paste")
			(net "GND")
		)
		(pad "5" smd oval
			(at 2.4 1.905 180)
			(size 0.6 2.2)
			(layers "F.Cu" "F.Mask" "F.Paste")
			(net "MAC_PPS_IN0-")
		)
		(pad "6" smd oval
			(at 2.4 0.635 180)
			(size 0.6 2.2)
			(layers "F.Cu" "F.Mask" "F.Paste")
			(net "MAC_PPS_IN0+")
		)
		(pad "7" smd oval
			(at 2.4 -0.635 180)
			(size 0.6 2.2)
			(layers "F.Cu" "F.Mask" "F.Paste")
			(net "MAC_PPS_IN1+")
		)
		(pad "8" smd oval
			(at 2.4 -1.905 180)
			(size 0.6 2.2)
			(layers "F.Cu" "F.Mask" "F.Paste")
			(net "MAC_PPS_IN1-")
		)
	)
	(footprint "Vault:FP-RC0603-0_55-MFG"
		(layer "F.Cu")
		(at 87.75686 82.56371)
		(property "Reference" "R40"
			(at -0.2286 1.473069 180)
			(unlocked yes)
			(layer "F.SilkS")
			(effects
				(font
					(size 0.762 0.762)
					(thickness 0.2286)
				)
			)
		)
		(property "Value" "DNI_100k"
			(at -2.998991 2.37408 270)
			(unlocked yes)
			(layer "F.SilkS")
			(hide yes)
			(effects
				(font
					(size 0.762 0.762)
					(thickness 0.2286)
				)
			)
		)
		(sheetname "02-USER_IO_STATUS")
		(sheetfile "02-USER_IO_STATUS.kicad_sch")
		(duplicate_pad_numbers_are_jumpers no)
		(fp_line
			(start -0.025 -0.45)
			(end 0.02501 -0.45)
			(stroke
				(width 0.2)
				(type solid)
			)
			(layer "F.SilkS")
		)
		(fp_line
			(start -0.025 0.45)
			(end 0.02501 0.45)
			(stroke
				(width 0.2)
				(type solid)
			)
			(layer "F.SilkS")
		)
		(fp_line
			(start -1.4 -0.55)
			(end 1.4 -0.55)
			(stroke
				(width 0.2)
				(type solid)
			)
			(layer "F.CrtYd")
		)
		(fp_line
			(start -1.4 0.55)
			(end -1.4 -0.55)
			(stroke
				(width 0.2)
				(type solid)
			)
			(layer "F.CrtYd")
		)
		(fp_line
			(start -1.4 0.55)
			(end 1.4 0.55)
			(stroke
				(width 0.2)
				(type solid)
			)
			(layer "F.CrtYd")
		)
		(fp_line
			(start 1.4 0.55)
			(end 1.4 -0.55)
			(stroke
				(width 0.2)
				(type solid)
			)
			(layer "F.CrtYd")
		)
		(fp_line
			(start -1.4 -0.55)
			(end 1.4 -0.55)
			(stroke
				(width 0.2)
				(type solid)
			)
			(layer "F.Fab")
		)
		(fp_line
			(start -1.4 0.55)
			(end -1.4 -0.55)
			(stroke
				(width 0.2)
				(type solid)
			)
			(layer "F.Fab")
		)
		(fp_line
			(start -1.4 0.55)
			(end 1.4 0.55)
			(stroke
				(width 0.2)
				(type solid)
			)
			(layer "F.Fab")
		)
		(fp_line
			(start -0.5 0)
			(end 0.5 0)
			(stroke
				(width 0.1)
				(type solid)
			)
			(layer "F.Fab")
		)
		(fp_line
			(start 0 0.5)
			(end 0 -0.5)
			(stroke
				(width 0.1)
				(type solid)
			)
			(layer "F.Fab")
		)
		(fp_line
			(start 1.4 0.55)
			(end 1.4 -0.55)
			(stroke
				(width 0.2)
				(type solid)
			)
			(layer "F.Fab")
		)
		(pad "1" smd rect
			(at -0.85 0)
			(size 0.9 0.8)
			(layers "F.Cu" "F.Mask" "F.Paste")
			(net "GND")
			(solder_mask_margin 0)
			(solder_paste_margin 0)
		)
		(pad "2" smd rect
			(at 0.85 0)
			(size 0.9 0.8)
			(layers "F.Cu" "F.Mask" "F.Paste")
			(net "NetR40_2")
			(solder_mask_margin 0)
			(solder_paste_margin 0)
		)
	)
)
